# BASEBOARD_FAB2 (Tioga Pass) — schematic netlist excerpt (pin names and nets, part order shuffled) for the footprints in the layout excerpt that follows; sources: Cadence DE-HDL packaged netlist, KiCad conversion of Wiwynn_Tioga_Pass_MB.brd

Q7E3  FET_N_DUAL  NTJD4001N FET  pkg SMLF  page 95
  SOURCE(0)  = GND
  GATE(0)  = FM_SYS_THROTTLE_LVC3
  DRAIN(0)  = H_CPU1_PROCHOT_G_N
  SOURCE(0)  = GND
  GATE(0)  = FM_SYS_THROTTLE_LVC3
  DRAIN(0)  = H_CPU0_PROCHOT_G_N

R3P43  RES  33.2 1% CHIP  pkg 0402  page 92 : A = FM_CPU_CATERR_LVT3_R2_N ; B = FM_CPU_CATERR_LVT3_N

(kicad_pcb
	(version 20260206)
	(generator "pcbnew")
	(generator_version "10.0")
	(general
		(thickness 1.6)
		(legacy_teardrops no)
	)
	(paper "A4")
	(title_block
		(title "Wiwynn_Tioga_Pass_MB.brd")
		(comment 1 "Tioga Pass / footprints 2600-2601 of 4770")
	)
	(layers
		(0 "F.Cu" signal "TOP")
		(4 "In1.Cu" signal "L2GND")
		(6 "In2.Cu" signal "L3")
		(8 "In3.Cu" signal "L4GND")
		(10 "In4.Cu" signal "L5")
		(12 "In5.Cu" signal "L6GND")
		(14 "In6.Cu" signal "L7VCC")
		(16 "In7.Cu" signal "L8VCC")
		(18 "In8.Cu" signal "L9GND")
		(20 "In9.Cu" signal "L10")
		(22 "In10.Cu" signal "L11GND")
		(24 "In11.Cu" signal "L12")
		(26 "In12.Cu" signal "L13GND")
		(2 "B.Cu" signal "BOTTOM")
		(9 "F.Adhes" user "F.Adhesive")
		(11 "B.Adhes" user "B.Adhesive")
		(13 "F.Paste" user "Package Geometry/Pastemask Top")
		(15 "B.Paste" user "Package Geometry/Pastemask Bottom")
		(5 "F.SilkS" user "Ref Des/Silkscreen Top")
		(7 "B.SilkS" user "Ref Des/Silkscreen Bottom")
		(1 "F.Mask" user "Board Geometry/Soldermask Top")
		(3 "B.Mask" user "Board Geometry/Soldermask Bottom")
		(17 "Dwgs.User" user "User.Drawings")
		(19 "Cmts.User" user "User.Comments")
		(21 "Eco1.User" user "User.Eco1")
		(23 "Eco2.User" user "User.Eco2")
		(25 "Edge.Cuts" user "Board Geometry/Outline")
		(27 "Margin" user)
		(31 "F.CrtYd" user "Package Geometry/Place Bound Top")
		(29 "B.CrtYd" user "Package Geometry/Place Bound Bottom")
		(35 "F.Fab" user "Ref Des/Assembly Top")
		(33 "B.Fab" user "Ref Des/Assembly Bottom")
	)
	(footprint ""
		(layer "B.Cu")
		(at 391.573512 -43.599608 180)
		(property "Reference" "Q7E3"
			(at -2.65938 -1.15697 0)
			(unlocked yes)
			(layer "B.SilkS")
			(effects
				(font
					(size 0.7874 0.5842)
					(thickness 0.1524)
				)
				(justify left mirror)
			)
		)
		(property "Value" ""
			(at 0 0 0)
			(layer "B.Fab")
			(effects
				(font
					(size 1.27 1.27)
				)
				(justify mirror)
			)
		)
		(duplicate_pad_numbers_are_jumpers no)
		(fp_circle
			(center 0.508 -0.7874)
			(end 0.381 -0.7874)
			(stroke
				(width 0.254)
				(type default)
			)
			(fill no)
			(layer "B.SilkS")
		)
		(fp_poly
			(pts
				(xy -0.2159 1.7526) (xy -1.5621 1.7526) (xy -1.5621 -0.4572) (xy -0.2159 -0.4572)
			)
			(stroke
				(width 0)
				(type default)
			)
			(fill no)
			(layer "B.CrtYd")
		)
		(fp_line
			(start -0.2159 1.75514)
			(end -1.5621 1.75514)
			(stroke
				(width 0.1)
				(type default)
			)
			(layer "B.Fab")
		)
		(fp_line
			(start -0.2159 -0.45466)
			(end -0.2159 1.75514)
			(stroke
				(width 0.1)
				(type default)
			)
			(layer "B.Fab")
		)
		(fp_line
			(start -1.5621 1.75514)
			(end -1.5621 -0.45466)
			(stroke
				(width 0.1)
				(type default)
			)
			(layer "B.Fab")
		)
		(fp_line
			(start -1.5621 -0.45466)
			(end -0.2159 -0.45466)
			(stroke
				(width 0.1)
				(type default)
			)
			(layer "B.Fab")
		)
		(fp_circle
			(center 0.508 -0.7874)
			(end 0.381 -0.7874)
			(stroke
				(width 0.254)
				(type default)
			)
			(fill no)
			(layer "B.Fab")
		)
		(pad "1" smd rect
			(at 0 0)
			(size 1.016 0.381)
			(layers "B.Cu" "B.Mask" "B.Paste")
			(net "GND")
		)
		(pad "2" smd rect
			(at 0 0.65024)
			(size 1.016 0.381)
			(layers "B.Cu" "B.Mask" "B.Paste")
			(net "FM_SYS_THROTTLE_LVC3")
		)
		(pad "3" smd rect
			(at 0 1.30048)
			(size 1.016 0.381)
			(layers "B.Cu" "B.Mask" "B.Paste")
			(net "H_CPU1_PROCHOT_G_N")
		)
		(pad "4" smd rect
			(at -1.778 1.30048)
			(size 1.016 0.381)
			(layers "B.Cu" "B.Mask" "B.Paste")
			(net "GND")
		)
		(pad "5" smd rect
			(at -1.778 0.65024)
			(size 1.016 0.381)
			(layers "B.Cu" "B.Mask" "B.Paste")
			(net "FM_SYS_THROTTLE_LVC3")
		)
		(pad "6" smd rect
			(at -1.778 0)
			(size 1.016 0.381)
			(layers "B.Cu" "B.Mask" "B.Paste")
			(net "H_CPU0_PROCHOT_G_N")
		)
		(zone
			(layer "B.Cu")
			(hatch none 0.5)
			(connect_pads
				(clearance 0)
			)
			(min_thickness 0.25)
			(keepout
				(tracks allowed)
				(vias not_allowed)
				(pads allowed)
				(copperpour not_allowed)
				(footprints allowed)
			)
			(placement
				(enabled no)
				(sheetname "")
			)
			(fill
				(thermal_gap 0.5)
				(thermal_bridge_width 0.5)
				(island_removal_mode 0)
			)
			(polygon
				(pts
					(xy 391.065512 -43.409108) (xy 392.081512 -43.409108) (xy 392.081512 -45.098208) (xy 391.065512 -45.098208)
				)
			)
		)
		(zone
			(layer "B.Cu")
			(hatch none 0.5)
			(connect_pads
				(clearance 0)
			)
			(min_thickness 0.25)
			(keepout
				(tracks allowed)
				(vias not_allowed)
				(pads allowed)
				(copperpour not_allowed)
				(footprints allowed)
			)
			(placement
				(enabled no)
				(sheetname "")
			)
			(fill
				(thermal_gap 0.5)
				(thermal_bridge_width 0.5)
				(island_removal_mode 0)
			)
			(polygon
				(pts
					(xy 392.843512 -43.409108) (xy 393.859512 -43.409108) (xy 393.859512 -45.098208) (xy 392.843512 -45.098208)
				)
			)
		)
	)
	(footprint ""
		(layer "B.Cu")
		(at 367.284 -62.2935 180)
		(property "Reference" "R3P43"
			(at 0 0 0)
			(layer "B.SilkS")
			(hide yes)
			(effects
				(font
					(size 1.27 1.27)
				)
				(justify mirror)
			)
		)
		(property "Value" ""
			(at 0 0 0)
			(layer "B.Fab")
			(effects
				(font
					(size 1.27 1.27)
				)
				(justify mirror)
			)
		)
		(duplicate_pad_numbers_are_jumpers no)
		(fp_poly
			(pts
				(xy 0.2794 -0.1016) (xy -0.2794 -0.1016) (xy -0.2794 0.9906) (xy 0.2794 0.9906)
			)
			(stroke
				(width 0)
				(type default)
			)
			(fill no)
			(layer "B.CrtYd")
		)
		(fp_line
			(start 0.2794 0.9906)
			(end -0.2794 0.9906)
			(stroke
				(width 0.1)
				(type default)
			)
			(layer "B.Fab")
		)
		(fp_line
			(start 0.2794 -0.1016)
			(end 0.2794 0.9906)
			(stroke
				(width 0.1)
				(type default)
			)
			(layer "B.Fab")
		)
		(fp_line
			(start -0.2794 0.9906)
			(end -0.2794 -0.1016)
			(stroke
				(width 0.1)
				(type default)
			)
			(layer "B.Fab")
		)
		(fp_line
			(start -0.2794 -0.1016)
			(end 0.2794 -0.1016)
			(stroke
				(width 0.1)
				(type default)
			)
			(layer "B.Fab")
		)
		(pad "1" smd rect
			(at 0 0)
			(size 0.508 0.508)
			(layers "B.Cu" "B.Mask" "B.Paste")
			(net "FM_CPU_CATERR_LVT3_R2_N")
		)
		(pad "2" smd rect
			(at 0 0.889)
			(size 0.508 0.508)
			(layers "B.Cu" "B.Mask" "B.Paste")
			(net "FM_CPU_CATERR_LVT3_N")
		)
		(zone
			(layer "B.Cu")
			(hatch none 0.5)
			(connect_pads
				(clearance 0)
			)
			(min_thickness 0.25)
			(keepout
				(tracks not_allowed)
				(vias allowed)
				(pads allowed)
				(copperpour not_allowed)
				(footprints allowed)
			)
			(placement
				(enabled no)
				(sheetname "")
			)
			(fill
				(thermal_gap 0.5)
				(thermal_bridge_width 0.5)
				(island_removal_mode 0)
			)
			(polygon
				(pts
					(xy 367.03 -62.9285) (xy 367.538 -62.9285) (xy 367.538 -62.5475) (xy 367.03 -62.5475)
				)
			)
		)
		(zone
			(layer "B.Cu")
			(hatch none 0.5)
			(connect_pads
				(clearance 0)
			)
			(min_thickness 0.25)
			(keepout
				(tracks allowed)
				(vias not_allowed)
				(pads allowed)
				(copperpour not_allowed)
				(footprints allowed)
			)
			(placement
				(enabled no)
				(sheetname "")
			)
			(fill
				(thermal_gap 0.5)
				(thermal_bridge_width 0.5)
				(island_removal_mode 0)
			)
			(polygon
				(pts
					(xy 367.03 -62.5475) (xy 367.538 -62.5475) (xy 367.538 -62.9285) (xy 367.03 -62.9285)
				)
			)
		)
	)
)
